FILE_TYPE = MACRO_DRAWING;
SET COLOR_WIRE YELLOW;
SET COLOR_PROP ORANGE;
SET COLOR_DOT WHITE;
SET COLOR_ARC YELLOW;
SET COLOR_BODY GREEN;
SET COLOR_NOTE PURPLE;
SET PROP_DISPLAY VALUE;
SET PAGE_NUMBER P128;
FORCEADD QUANTA_TITLE_BLOCK_C..1
(0 0);
FORCEPROP 1 LAST CUSTOM_TXT_CDS <NAME_2>
J 0
(-3175 50);
FORCEPROP 1 LAST CUSTOM_TXT_CDS <NAME_1>
J 0
(-3175 175);
FORCEPROP 1 LAST CUSTOM_TXT_CDS <Q_NUMBER>
J 0
(-1403 103);
DISPLAY 1.212766 (-1403 103);
FORCEPROP 1 LAST CUSTOM_TXT_CDS <Q_PROJ>
J 0
(-2382 102);
DISPLAY 1.212766 (-2382 102);
FORCEPROP 1 LAST CUSTOM_TXT_CDS <Q_REV>
J 0
(-184 103);
DISPLAY 1.212766 (-184 103);
FORCEPROP 1 LAST CUSTOM_TXT_CDS <CON_LAST_MODIFIED>
J 0
(-1885 15);
DISPLAY 0.978723 (-1885 15);
FORCEPROP 1 LAST CUSTOM_TXT_CDS <CON_PAGE_NUM> OF <CON_TOTAL_PAGES>
J 0
(-446 18);
DISPLAY 0.978723 (-446 18);
FORCEPROP 1 LAST Q_TITLE M.2 CONN (1/2)
J 0
(-9366 26);
DISPLAY 2.446809 (-9366 26);
PAINT GREEN (-9366 26);
FORCEPROP 1 LAST Q_DEPT BU9
J 1
(-3763 49);
DISPLAY 1.957447 (-3763 49);
PAINT GREEN (-3763 49);
FORCEPROP 2 LAST CDS_LIB pure_quanta
J 0
(0 0);
DISPLAY INVISIBLE (0 0);
FORCEPROP 1 LAST CDS_LMAN_SYM_OUTLINE -9475,6775,100,-125
J 0
(0 0);
DISPLAY 0.468085 (0 0);
PAINT GREEN (0 0);
DISPLAY INVISIBLE (0 0);
FORCEPROP 2 LAST PAGE_BORDER TRUE
J 0
(-7890 5250);
DISPLAY 0.638298 (-7890 5250);
PAINT PINK (-7890 5250);
DISPLAY INVISIBLE (-7890 5250);
FORCEPROP 1 LAST COMMENT_BODY TRUE
J 0
(12 -13);
DISPLAY 0.978723 (12 -13);
PAINT GREEN (12 -13);
DISPLAY INVISIBLE (12 -13);
FORCEPROP 2 LAST CDS_XR_PAGE_TITLE CR-128 : @T6G_MB_LIB.T6G(SCH_1):PAGE128
J 0
(-7890 5250);
DISPLAY 0.638298 (-7890 5250);
PAINT PINK (-7890 5250);
DISPLAY INVISIBLE (-7890 5250);
FORCEPROP 2 LAST CUSTOM_TXT_CDS <XR_PAGE_TITLE>
J 0
(-7890 5250);
DISPLAY 0.638298 (-7890 5250);
PAINT PINK (-7890 5250);
DISPLAY INVISIBLE (-7890 5250);
FORCEPROP 0 LAST CDS_CON_LAST_MODIFIED Wed Mar 09 18:20:43 2022
J 0
(-1885 15);
DISPLAY INVISIBLE (-1885 15);
QUIT
